(kicad_pcb
	(version 20260206)
	(generator "pcbnew")
	(generator_version "10.0")
	(general
		(thickness 1.6)
		(legacy_teardrops no)
	)
	(paper "A4")
	(title_block
		(title "01162023_DA0F0TEBIF0_F0T_Expander_BD_F_brd_V02_OCP.brd")
		(comment 1 "Grand Teton / footprints 3604-3608 of 9728")
	)
	(layers
		(0 "F.Cu" signal "TOP")
		(4 "In1.Cu" signal "GND")
		(6 "In2.Cu" signal "VCC")
		(8 "In3.Cu" signal "VCC1")
		(10 "In4.Cu" signal "GND1")
		(12 "In5.Cu" signal "IN1")
		(14 "In6.Cu" signal "GND2")
		(16 "In7.Cu" signal "IN2")
		(18 "In8.Cu" signal "GND3")
		(20 "In9.Cu" signal "IN3")
		(22 "In10.Cu" signal "GND4")
		(24 "In11.Cu" signal "IN4")
		(26 "In12.Cu" signal "GND5")
		(28 "In13.Cu" signal "IN5")
		(30 "In14.Cu" signal "GND6")
		(32 "In15.Cu" signal "IN6")
		(34 "In16.Cu" signal "GND7")
		(2 "B.Cu" signal "BOTTOM")
		(9 "F.Adhes" user "F.Adhesive")
		(11 "B.Adhes" user "B.Adhesive")
		(13 "F.Paste" user "Package Geometry/Pastemask Top")
		(15 "B.Paste" user "Package Geometry/Pastemask Bottom")
		(5 "F.SilkS" user "Ref Des/Silkscreen Top")
		(7 "B.SilkS" user "Ref Des/Silkscreen Bottom")
		(1 "F.Mask" user "Board Geometry/Soldermask Top")
		(3 "B.Mask" user "Board Geometry/Soldermask Bottom")
		(17 "Dwgs.User" user "User.Drawings")
		(19 "Cmts.User" user "User.Comments")
		(21 "Eco1.User" user "User.Eco1")
		(23 "Eco2.User" user "User.Eco2")
		(25 "Edge.Cuts" user "Board Geometry/Outline")
		(27 "Margin" user)
		(31 "F.CrtYd" user "Package Geometry/Place Bound Top")
		(29 "B.CrtYd" user "Package Geometry/Place Bound Bottom")
		(35 "F.Fab" user "Ref Des/Assembly Top")
		(33 "B.Fab" user "Ref Des/Assembly Bottom")
	)
	(footprint ""
		(layer "F.Cu")
		(at 426.567854 -56.353456)
		(property "Reference" "C2874"
			(at 0 0 0)
			(layer "F.SilkS")
			(hide yes)
			(effects
				(font
					(size 1.27 1.27)
				)
			)
		)
		(property "Value" ""
			(at 0 0 0)
			(layer "F.Fab")
			(effects
				(font
					(size 1.27 1.27)
				)
			)
		)
		(duplicate_pad_numbers_are_jumpers no)
		(fp_line
			(start -0.7874 -0.4064)
			(end 0.7874 -0.4064)
			(stroke
				(width 0.1524)
				(type default)
			)
			(layer "F.SilkS")
		)
		(fp_line
			(start -0.7874 0.4064)
			(end -0.7874 -0.4064)
			(stroke
				(width 0.1524)
				(type default)
			)
			(layer "F.SilkS")
		)
		(fp_line
			(start 0.7874 -0.4064)
			(end 0.7874 0.4064)
			(stroke
				(width 0.1524)
				(type default)
			)
			(layer "F.SilkS")
		)
		(fp_line
			(start 0.7874 0.4064)
			(end -0.7874 0.4064)
			(stroke
				(width 0.1524)
				(type default)
			)
			(layer "F.SilkS")
		)
		(fp_line
			(start -0.67945 -0.305054)
			(end -0.12065 -0.305054)
			(stroke
				(width 0.1)
				(type default)
			)
			(layer "F.Fab")
		)
		(fp_line
			(start -0.67945 0.3048)
			(end -0.67945 -0.305054)
			(stroke
				(width 0.1)
				(type default)
			)
			(layer "F.Fab")
		)
		(fp_line
			(start -0.12065 -0.305054)
			(end -0.12065 -0.2794)
			(stroke
				(width 0.1)
				(type default)
			)
			(layer "F.Fab")
		)
		(fp_line
			(start -0.12065 -0.2794)
			(end 0.12065 -0.2794)
			(stroke
				(width 0.1)
				(type default)
			)
			(layer "F.Fab")
		)
		(fp_line
			(start -0.12065 0.2794)
			(end -0.12065 0.3048)
			(stroke
				(width 0.1)
				(type default)
			)
			(layer "F.Fab")
		)
		(fp_line
			(start -0.12065 0.3048)
			(end -0.67945 0.3048)
			(stroke
				(width 0.1)
				(type default)
			)
			(layer "F.Fab")
		)
		(fp_line
			(start 0.120396 0.2794)
			(end -0.12065 0.2794)
			(stroke
				(width 0.1)
				(type default)
			)
			(layer "F.Fab")
		)
		(fp_line
			(start 0.120396 0.3048)
			(end 0.120396 0.2794)
			(stroke
				(width 0.1)
				(type default)
			)
			(layer "F.Fab")
		)
		(fp_line
			(start 0.12065 -0.3048)
			(end 0.67945 -0.3048)
			(stroke
				(width 0.1)
				(type default)
			)
			(layer "F.Fab")
		)
		(fp_line
			(start 0.12065 -0.2794)
			(end 0.12065 -0.3048)
			(stroke
				(width 0.1)
				(type default)
			)
			(layer "F.Fab")
		)
		(fp_line
			(start 0.67945 -0.3048)
			(end 0.67945 0.3048)
			(stroke
				(width 0.1)
				(type default)
			)
			(layer "F.Fab")
		)
		(fp_line
			(start 0.67945 0.3048)
			(end 0.120396 0.3048)
			(stroke
				(width 0.1)
				(type default)
			)
			(layer "F.Fab")
		)
		(pad "1" smd circle
			(at -0.40005 0)
			(size 0 0)
			(layers "F.Cu" "F.Mask" "F.Paste")
			(net "SSD14_PWR_EN_R")
		)
		(pad "2" smd circle
			(at 0.40005 0)
			(size 0 0)
			(layers "F.Cu" "F.Mask" "F.Paste")
			(net "GND")
		)
	)
	(footprint ""
		(layer "F.Cu")
		(at 453.762364 -22.937216 90)
		(property "Reference" "R1740"
			(at 0 0 90)
			(layer "F.SilkS")
			(hide yes)
			(effects
				(font
					(size 1.27 1.27)
				)
			)
		)
		(property "Value" ""
			(at 0 0 90)
			(layer "F.Fab")
			(effects
				(font
					(size 1.27 1.27)
				)
			)
		)
		(duplicate_pad_numbers_are_jumpers no)
		(fp_line
			(start 0.7874 -0.4064)
			(end 0.7874 0.4064)
			(stroke
				(width 0.1524)
				(type default)
			)
			(layer "F.SilkS")
		)
		(fp_line
			(start -0.7874 -0.4064)
			(end 0.7874 -0.4064)
			(stroke
				(width 0.1524)
				(type default)
			)
			(layer "F.SilkS")
		)
		(fp_line
			(start 0.7874 0.4064)
			(end -0.7874 0.4064)
			(stroke
				(width 0.1524)
				(type default)
			)
			(layer "F.SilkS")
		)
		(fp_line
			(start -0.7874 0.4064)
			(end -0.7874 -0.4064)
			(stroke
				(width 0.1524)
				(type default)
			)
			(layer "F.SilkS")
		)
		(fp_line
			(start -0.12065 -0.305054)
			(end -0.12065 -0.2794)
			(stroke
				(width 0.1)
				(type default)
			)
			(layer "F.Fab")
		)
		(fp_line
			(start -0.67945 -0.305054)
			(end -0.12065 -0.305054)
			(stroke
				(width 0.1)
				(type default)
			)
			(layer "F.Fab")
		)
		(fp_line
			(start 0.67945 -0.3048)
			(end 0.67945 0.3048)
			(stroke
				(width 0.1)
				(type default)
			)
			(layer "F.Fab")
		)
		(fp_line
			(start 0.12065 -0.3048)
			(end 0.67945 -0.3048)
			(stroke
				(width 0.1)
				(type default)
			)
			(layer "F.Fab")
		)
		(fp_line
			(start 0.12065 -0.2794)
			(end 0.12065 -0.3048)
			(stroke
				(width 0.1)
				(type default)
			)
			(layer "F.Fab")
		)
		(fp_line
			(start -0.12065 -0.2794)
			(end 0.12065 -0.2794)
			(stroke
				(width 0.1)
				(type default)
			)
			(layer "F.Fab")
		)
		(fp_line
			(start 0.120396 0.2794)
			(end -0.12065 0.2794)
			(stroke
				(width 0.1)
				(type default)
			)
			(layer "F.Fab")
		)
		(fp_line
			(start -0.12065 0.2794)
			(end -0.12065 0.3048)
			(stroke
				(width 0.1)
				(type default)
			)
			(layer "F.Fab")
		)
		(fp_line
			(start 0.67945 0.3048)
			(end 0.120396 0.3048)
			(stroke
				(width 0.1)
				(type default)
			)
			(layer "F.Fab")
		)
		(fp_line
			(start 0.120396 0.3048)
			(end 0.120396 0.2794)
			(stroke
				(width 0.1)
				(type default)
			)
			(layer "F.Fab")
		)
		(fp_line
			(start -0.12065 0.3048)
			(end -0.67945 0.3048)
			(stroke
				(width 0.1)
				(type default)
			)
			(layer "F.Fab")
		)
		(fp_line
			(start -0.67945 0.3048)
			(end -0.67945 -0.305054)
			(stroke
				(width 0.1)
				(type default)
			)
			(layer "F.Fab")
		)
		(pad "1" smd circle
			(at -0.40005 0 90)
			(size 0 0)
			(layers "F.Cu" "F.Mask" "F.Paste")
			(net "SMB_BIC_I2C9_MUX1_SSD15_R_SDA")
		)
		(pad "2" smd circle
			(at 0.40005 0 90)
			(size 0 0)
			(layers "F.Cu" "F.Mask" "F.Paste")
			(net "SMB_ISO_SSD15_SDA")
		)
	)
	(footprint ""
		(layer "F.Cu")
		(at 10.221722 -306.281836 180)
		(property "Reference" "PU16"
			(at 4.075684 -3.873246 0)
			(unlocked yes)
			(layer "F.SilkS")
			(effects
				(font
					(size 0.7874 0.5842)
					(thickness 0.1524)
				)
				(justify left)
			)
		)
		(property "Value" ""
			(at 0 0 180)
			(layer "F.Fab")
			(effects
				(font
					(size 1.27 1.27)
				)
			)
		)
		(duplicate_pad_numbers_are_jumpers no)
		(fp_line
			(start 1.549908 2.050034)
			(end 1.549908 1.9304)
			(stroke
				(width 0.1524)
				(type default)
			)
			(layer "F.SilkS")
		)
		(fp_line
			(start 1.549908 -1.9812)
			(end 1.549908 -2.050034)
			(stroke
				(width 0.1524)
				(type default)
			)
			(layer "F.SilkS")
		)
		(fp_line
			(start 1.549908 -2.050034)
			(end 0.5842 -2.050034)
			(stroke
				(width 0.1524)
				(type default)
			)
			(layer "F.SilkS")
		)
		(fp_line
			(start 0.3048 -2.4638)
			(end 0.3048 -3.2258)
			(stroke
				(width 0.1524)
				(type default)
			)
			(layer "F.SilkS")
		)
		(fp_line
			(start 0 2.050034)
			(end 1.549908 2.050034)
			(stroke
				(width 0.1524)
				(type default)
			)
			(layer "F.SilkS")
		)
		(fp_line
			(start -0.3048 2.4638)
			(end -0.3048 3.2258)
			(stroke
				(width 0.1524)
				(type default)
			)
			(layer "F.SilkS")
		)
		(fp_line
			(start -0.5842 -2.050034)
			(end -1.549908 -2.050034)
			(stroke
				(width 0.1524)
				(type default)
			)
			(layer "F.SilkS")
		)
		(fp_line
			(start -1.549908 2.050034)
			(end -0.5842 2.050034)
			(stroke
				(width 0.1524)
				(type default)
			)
			(layer "F.SilkS")
		)
		(fp_line
			(start -1.549908 1.9812)
			(end -1.549908 2.050034)
			(stroke
				(width 0.1524)
				(type default)
			)
			(layer "F.SilkS")
		)
		(fp_line
			(start -1.549908 -2.050034)
			(end -1.549908 -1.9812)
			(stroke
				(width 0.1524)
				(type default)
			)
			(layer "F.SilkS")
		)
		(fp_line
			(start -1.9812 0)
			(end -2.3622 0)
			(stroke
				(width 0.1524)
				(type default)
			)
			(layer "F.SilkS")
		)
		(fp_poly
			(pts
				(xy -2.9464 -2.208022) (xy -2.9464 -1.192022) (xy -1.9304 -1.700022)
			)
			(stroke
				(width 0)
				(type default)
			)
			(fill yes)
			(layer "F.SilkS")
		)
		(fp_line
			(start 1.549908 2.050034)
			(end 1.549908 -2.050034)
			(stroke
				(width 0.1)
				(type default)
			)
			(layer "F.Fab")
		)
		(fp_line
			(start 1.549908 -2.050034)
			(end -1.549908 -2.050034)
			(stroke
				(width 0.1)
				(type default)
			)
			(layer "F.Fab")
		)
		(fp_line
			(start 0.3048 -2.4638)
			(end 0.3048 -3.2258)
			(stroke
				(width 0.1)
				(type default)
			)
			(layer "F.Fab")
		)
		(fp_line
			(start -0.3048 2.4638)
			(end -0.3048 3.2258)
			(stroke
				(width 0.1)
				(type default)
			)
			(layer "F.Fab")
		)
		(fp_line
			(start -1.549908 2.050034)
			(end 1.549908 2.050034)
			(stroke
				(width 0.1)
				(type default)
			)
			(layer "F.Fab")
		)
		(fp_line
			(start -1.549908 -2.050034)
			(end -1.549908 2.050034)
			(stroke
				(width 0.1)
				(type default)
			)
			(layer "F.Fab")
		)
		(fp_line
			(start -1.9812 0)
			(end -2.3622 0)
			(stroke
				(width 0.1)
				(type default)
			)
			(layer "F.Fab")
		)
		(fp_poly
			(pts
				(xy -2.9464 -2.208022) (xy -2.9464 -1.192022) (xy -1.9304 -1.700022)
			)
			(stroke
				(width 0)
				(type default)
			)
			(fill yes)
			(layer "F.Fab")
		)
		(fp_text user "11_18"
			(at 2.512568 0.9906 90)
			(unlocked yes)
			(layer "F.SilkS")
			(effects
				(font
					(size 0.635 0.4064)
					(thickness 0.1524)
				)
			)
		)
		(fp_text user "19"
			(at 1.823974 -2.636012 90)
			(unlocked yes)
			(layer "F.SilkS")
			(effects
				(font
					(size 0.635 0.4064)
					(thickness 0.1524)
				)
			)
		)
		(fp_text user "9"
			(at -1.913128 2.378964 90)
			(unlocked yes)
			(layer "F.SilkS")
			(effects
				(font
					(size 0.635 0.4064)
					(thickness 0.1524)
				)
			)
		)
		(fp_text user "11_18"
			(at 2.512568 0.9906 90)
			(unlocked yes)
			(layer "F.Fab")
			(effects
				(font
					(size 0.635 0.4064)
					(thickness 0.1524)
				)
			)
		)
		(fp_text user "19"
			(at 2.410968 -2.159 90)
			(unlocked yes)
			(layer "F.Fab")
			(effects
				(font
					(size 0.635 0.4064)
					(thickness 0.1524)
				)
			)
		)
		(fp_text user "9"
			(at -2.338832 2.0574 90)
			(unlocked yes)
			(layer "F.Fab")
			(effects
				(font
					(size 0.635 0.4064)
					(thickness 0.1524)
				)
			)
		)
		(pad "1" smd rect
			(at -1.35001 -1.700022 270)
			(size 0.3048 0.9144)
			(layers "F.Cu" "F.Mask" "F.Paste")
			(net "SW_P1V25_PEX0_BT")
		)
		(pad "2" smd rect
			(at -1.400048 -1.199896 270)
			(size 0.1778 0.8128)
			(layers "F.Cu" "F.Mask" "F.Paste")
			(net "GND")
		)
		(pad "3" smd rect
			(at -1.400048 -0.8001 270)
			(size 0.1778 0.8128)
			(layers "F.Cu" "F.Mask" "F.Paste")
			(net "P1V25_PEX0_CS")
		)
		(pad "4" smd rect
			(at -1.400048 -0.40005 270)
			(size 0.1778 0.8128)
			(layers "F.Cu" "F.Mask" "F.Paste")
			(net "GND")
		)
		(pad "5" smd rect
			(at -1.400048 0 270)
			(size 0.1778 0.8128)
			(layers "F.Cu" "F.Mask" "F.Paste")
			(net "P1V25_PEX0_REF")
		)
		(pad "6" smd rect
			(at -1.400048 0.40005 270)
			(size 0.1778 0.8128)
			(layers "F.Cu" "F.Mask" "F.Paste")
			(net "SH_P1V25_PEX0_FB_N")
		)
		(pad "7" smd rect
			(at -1.400048 0.8001 270)
			(size 0.1778 0.8128)
			(layers "F.Cu" "F.Mask" "F.Paste")
			(net "P1V25_PEX0_FB")
		)
		(pad "8" smd rect
			(at -1.400048 1.199896 270)
			(size 0.1778 0.8128)
			(layers "F.Cu" "F.Mask" "F.Paste")
			(net "P1V25_PEX0_EN")
		)
		(pad "9" smd rect
			(at -1.400048 1.700022 270)
			(size 0.3048 0.8128)
			(layers "F.Cu" "F.Mask" "F.Paste")
			(net "PWRGD_P1V25_PEX0")
		)
		(pad "10" smd rect
			(at -0.299974 1.299972 180)
			(size 0.3048 2.0066)
			(layers "F.Cu" "F.Mask" "F.Paste")
			(net "SW_P12V_P1V25_PEX0_FLT")
		)
		(pad "11_18" smd circle
			(at 1.175004 0.275082 180)
			(size 0 0)
			(layers "F.Cu" "F.Mask" "F.Paste")
			(net "GND")
		)
		(pad "19" smd rect
			(at 1.400048 -1.700022 90)
			(size 0.3048 0.8128)
			(layers "F.Cu" "F.Mask" "F.Paste")
			(net "P1V25_PEX0_VCC")
		)
		(pad "20" smd rect
			(at 0.299974 -1.299972 180)
			(size 0.3048 2.0066)
			(layers "F.Cu" "F.Mask" "F.Paste")
			(net "SW_P1V25_PEX0_PH")
		)
		(pad "21" smd rect
			(at -0.299974 -1.299972 180)
			(size 0.3048 2.0066)
			(layers "F.Cu" "F.Mask" "F.Paste")
			(net "SW_P12V_P1V25_PEX0_FLT")
		)
	)
	(footprint ""
		(layer "F.Cu")
		(at 122.689366 -313.620404 180)
		(property "Reference" "L28"
			(at 3.502914 -1.171448 90)
			(unlocked yes)
			(layer "F.SilkS")
			(effects
				(font
					(size 0.7874 0.5842)
					(thickness 0.1524)
				)
				(justify left)
			)
		)
		(property "Value" ""
			(at 0 0 180)
			(layer "F.Fab")
			(effects
				(font
					(size 1.27 1.27)
				)
			)
		)
		(duplicate_pad_numbers_are_jumpers no)
		(fp_line
			(start 2.248154 4.9911)
			(end 2.248154 1.556512)
			(stroke
				(width 0.1524)
				(type default)
			)
			(layer "F.SilkS")
		)
		(fp_line
			(start 2.248154 -1.660652)
			(end 2.248154 -4.9911)
			(stroke
				(width 0.1524)
				(type default)
			)
			(layer "F.SilkS")
		)
		(fp_line
			(start 2.248154 -4.9911)
			(end -2.248154 -4.9911)
			(stroke
				(width 0.1524)
				(type default)
			)
			(layer "F.SilkS")
		)
		(fp_line
			(start -2.248154 4.9911)
			(end 2.248154 4.9911)
			(stroke
				(width 0.1524)
				(type default)
			)
			(layer "F.SilkS")
		)
		(fp_line
			(start -2.248154 1.622552)
			(end -2.248154 4.9911)
			(stroke
				(width 0.1524)
				(type default)
			)
			(layer "F.SilkS")
		)
		(fp_line
			(start -2.248154 -4.9911)
			(end -2.248154 -1.693418)
			(stroke
				(width 0.1524)
				(type default)
			)
			(layer "F.SilkS")
		)
		(fp_line
			(start 1.700022 0.899922)
			(end 1.700022 -0.899922)
			(stroke
				(width 0.1)
				(type default)
			)
			(layer "F.Fab")
		)
		(fp_line
			(start 1.700022 -0.899922)
			(end -1.700022 -0.899922)
			(stroke
				(width 0.1)
				(type default)
			)
			(layer "F.Fab")
		)
		(fp_line
			(start -1.700022 0.899922)
			(end 1.700022 0.899922)
			(stroke
				(width 0.1)
				(type default)
			)
			(layer "F.Fab")
		)
		(fp_line
			(start -1.700022 -0.899922)
			(end -1.700022 0.899922)
			(stroke
				(width 0.1)
				(type default)
			)
			(layer "F.Fab")
		)
		(pad "1" smd rect
			(at -1.575054 0 180)
			(size 1.1684 9.8044)
			(layers "F.Cu" "F.Mask" "F.Paste")
			(net "P0V8_PEX1")
		)
		(pad "2" smd rect
			(at 1.575054 0 180)
			(size 1.1684 9.8044)
			(layers "F.Cu" "F.Mask" "F.Paste")
			(net "P0V8_SERDES_VDDA_PEX1")
		)
	)
	(footprint ""
		(layer "F.Cu")
		(at 213.357968 -72.766682 90)
		(property "Reference" "PC855"
			(at 0 0 90)
			(layer "F.SilkS")
			(hide yes)
			(effects
				(font
					(size 1.27 1.27)
				)
			)
		)
		(property "Value" ""
			(at 0 0 90)
			(layer "F.Fab")
			(effects
				(font
					(size 1.27 1.27)
				)
			)
		)
		(duplicate_pad_numbers_are_jumpers no)
		(fp_line
			(start 0.7874 -0.4064)
			(end 0.7874 0.4064)
			(stroke
				(width 0.1524)
				(type default)
			)
			(layer "F.SilkS")
		)
		(fp_line
			(start -0.7874 -0.4064)
			(end 0.7874 -0.4064)
			(stroke
				(width 0.1524)
				(type default)
			)
			(layer "F.SilkS")
		)
		(fp_line
			(start 0.7874 0.4064)
			(end -0.7874 0.4064)
			(stroke
				(width 0.1524)
				(type default)
			)
			(layer "F.SilkS")
		)
		(fp_line
			(start -0.7874 0.4064)
			(end -0.7874 -0.4064)
			(stroke
				(width 0.1524)
				(type default)
			)
			(layer "F.SilkS")
		)
		(fp_line
			(start -0.12065 -0.305054)
			(end -0.12065 -0.2794)
			(stroke
				(width 0.1)
				(type default)
			)
			(layer "F.Fab")
		)
		(fp_line
			(start -0.67945 -0.305054)
			(end -0.12065 -0.305054)
			(stroke
				(width 0.1)
				(type default)
			)
			(layer "F.Fab")
		)
		(fp_line
			(start 0.67945 -0.3048)
			(end 0.67945 0.3048)
			(stroke
				(width 0.1)
				(type default)
			)
			(layer "F.Fab")
		)
		(fp_line
			(start 0.12065 -0.3048)
			(end 0.67945 -0.3048)
			(stroke
				(width 0.1)
				(type default)
			)
			(layer "F.Fab")
		)
		(fp_line
			(start 0.12065 -0.2794)
			(end 0.12065 -0.3048)
			(stroke
				(width 0.1)
				(type default)
			)
			(layer "F.Fab")
		)
		(fp_line
			(start -0.12065 -0.2794)
			(end 0.12065 -0.2794)
			(stroke
				(width 0.1)
				(type default)
			)
			(layer "F.Fab")
		)
		(fp_line
			(start 0.120396 0.2794)
			(end -0.12065 0.2794)
			(stroke
				(width 0.1)
				(type default)
			)
			(layer "F.Fab")
		)
		(fp_line
			(start -0.12065 0.2794)
			(end -0.12065 0.3048)
			(stroke
				(width 0.1)
				(type default)
			)
			(layer "F.Fab")
		)
		(fp_line
			(start 0.67945 0.3048)
			(end 0.120396 0.3048)
			(stroke
				(width 0.1)
				(type default)
			)
			(layer "F.Fab")
		)
		(fp_line
			(start 0.120396 0.3048)
			(end 0.120396 0.2794)
			(stroke
				(width 0.1)
				(type default)
			)
			(layer "F.Fab")
		)
		(fp_line
			(start -0.12065 0.3048)
			(end -0.67945 0.3048)
			(stroke
				(width 0.1)
				(type default)
			)
			(layer "F.Fab")
		)
		(fp_line
			(start -0.67945 0.3048)
			(end -0.67945 -0.305054)
			(stroke
				(width 0.1)
				(type default)
			)
			(layer "F.Fab")
		)
		(pad "1" smd circle
			(at -0.40005 0 90)
			(size 0 0)
			(layers "F.Cu" "F.Mask" "F.Paste")
			(net "P12V_SSD7_CO_MODE")
		)
		(pad "2" smd circle
			(at 0.40005 0 90)
			(size 0 0)
			(layers "F.Cu" "F.Mask" "F.Paste")
			(net "GND")
		)
	)
)
